# S9S_MB_2U (Grand Teton) — schematic netlist excerpt (pin names and nets, part order shuffled) for the footprints in the layout excerpt that follows; sources: Cadence DE-HDL packaged netlist, KiCad conversion of 03242023_DA0F0TMBIJ0_F0T_Motherboard_J_brd_V01_OCP.brd

R4148  Q_RES  33.2 1% CHIP  pkg 0402LF  page 215 : A = GPU_3V3IO_RSVD5_FFU_ISO ; B = GPU_3V3IO_RSVD5_FFU_ISO_R
PR4246  Q_RES  0 5% CHIP  pkg 0402LF  page 292 : A = NC_PVCCINFAON_CPU1_ACSP7 ; B = GND

(kicad_pcb
	(version 20260206)
	(generator "pcbnew")
	(generator_version "10.0")
	(general
		(thickness 1.6)
		(legacy_teardrops no)
	)
	(paper "A4")
	(title_block
		(title "03242023_DA0F0TMBIJ0_F0T_Motherboard_J_brd_V01_OCP.brd")
		(comment 1 "Grand Teton / footprints 2744-2745 of 6105")
	)
	(layers
		(0 "F.Cu" signal "TOP")
		(4 "In1.Cu" signal "GND")
		(6 "In2.Cu" signal "IN1")
		(8 "In3.Cu" signal "GND1")
		(10 "In4.Cu" signal "IN2")
		(12 "In5.Cu" signal "GND2")
		(14 "In6.Cu" signal "IN3")
		(16 "In7.Cu" signal "GND3")
		(18 "In8.Cu" signal "VCC")
		(20 "In9.Cu" signal "VCC1")
		(22 "In10.Cu" signal "GND4")
		(24 "In11.Cu" signal "IN4")
		(26 "In12.Cu" signal "GND5")
		(28 "In13.Cu" signal "IN5")
		(30 "In14.Cu" signal "GND6")
		(32 "In15.Cu" signal "IN6")
		(34 "In16.Cu" signal "GND7")
		(2 "B.Cu" signal "BOTTOM")
		(9 "F.Adhes" user "F.Adhesive")
		(11 "B.Adhes" user "B.Adhesive")
		(13 "F.Paste" user "Package Geometry/Pastemask Top")
		(15 "B.Paste" user "Package Geometry/Pastemask Bottom")
		(5 "F.SilkS" user "Ref Des/Silkscreen Top")
		(7 "B.SilkS" user "Ref Des/Silkscreen Bottom")
		(1 "F.Mask" user "Board Geometry/Soldermask Top")
		(3 "B.Mask" user "Board Geometry/Soldermask Bottom")
		(17 "Dwgs.User" user "User.Drawings")
		(19 "Cmts.User" user "User.Comments")
		(21 "Eco1.User" user "User.Eco1")
		(23 "Eco2.User" user "User.Eco2")
		(25 "Edge.Cuts" user "Board Geometry/Outline")
		(27 "Margin" user)
		(31 "F.CrtYd" user "Package Geometry/Place Bound Top")
		(29 "B.CrtYd" user "Package Geometry/Place Bound Bottom")
		(35 "F.Fab" user "Ref Des/Assembly Top")
		(33 "B.Fab" user "Ref Des/Assembly Bottom")
	)
	(footprint ""
		(layer "F.Cu")
		(at 201.00036 -111.724948 180)
		(property "Reference" "R4148"
			(at 0 0 180)
			(layer "F.SilkS")
			(hide yes)
			(effects
				(font
					(size 1.27 1.27)
				)
			)
		)
		(property "Value" ""
			(at 0 0 180)
			(layer "F.Fab")
			(effects
				(font
					(size 1.27 1.27)
				)
			)
		)
		(duplicate_pad_numbers_are_jumpers no)
		(fp_line
			(start 0.7874 0.4064)
			(end -0.7874 0.4064)
			(stroke
				(width 0.1524)
				(type default)
			)
			(layer "F.SilkS")
		)
		(fp_line
			(start 0.7874 -0.4064)
			(end 0.7874 0.4064)
			(stroke
				(width 0.1524)
				(type default)
			)
			(layer "F.SilkS")
		)
		(fp_line
			(start -0.7874 0.4064)
			(end -0.7874 -0.4064)
			(stroke
				(width 0.1524)
				(type default)
			)
			(layer "F.SilkS")
		)
		(fp_line
			(start -0.7874 -0.4064)
			(end 0.7874 -0.4064)
			(stroke
				(width 0.1524)
				(type default)
			)
			(layer "F.SilkS")
		)
		(fp_line
			(start 0.67945 0.3048)
			(end 0.120396 0.3048)
			(stroke
				(width 0.1)
				(type default)
			)
			(layer "F.Fab")
		)
		(fp_line
			(start 0.67945 -0.3048)
			(end 0.67945 0.3048)
			(stroke
				(width 0.1)
				(type default)
			)
			(layer "F.Fab")
		)
		(fp_line
			(start 0.12065 -0.2794)
			(end 0.12065 -0.3048)
			(stroke
				(width 0.1)
				(type default)
			)
			(layer "F.Fab")
		)
		(fp_line
			(start 0.12065 -0.3048)
			(end 0.67945 -0.3048)
			(stroke
				(width 0.1)
				(type default)
			)
			(layer "F.Fab")
		)
		(fp_line
			(start 0.120396 0.3048)
			(end 0.120396 0.2794)
			(stroke
				(width 0.1)
				(type default)
			)
			(layer "F.Fab")
		)
		(fp_line
			(start 0.120396 0.2794)
			(end -0.12065 0.2794)
			(stroke
				(width 0.1)
				(type default)
			)
			(layer "F.Fab")
		)
		(fp_line
			(start -0.12065 0.3048)
			(end -0.67945 0.3048)
			(stroke
				(width 0.1)
				(type default)
			)
			(layer "F.Fab")
		)
		(fp_line
			(start -0.12065 0.2794)
			(end -0.12065 0.3048)
			(stroke
				(width 0.1)
				(type default)
			)
			(layer "F.Fab")
		)
		(fp_line
			(start -0.12065 -0.2794)
			(end 0.12065 -0.2794)
			(stroke
				(width 0.1)
				(type default)
			)
			(layer "F.Fab")
		)
		(fp_line
			(start -0.12065 -0.305054)
			(end -0.12065 -0.2794)
			(stroke
				(width 0.1)
				(type default)
			)
			(layer "F.Fab")
		)
		(fp_line
			(start -0.67945 0.3048)
			(end -0.67945 -0.305054)
			(stroke
				(width 0.1)
				(type default)
			)
			(layer "F.Fab")
		)
		(fp_line
			(start -0.67945 -0.305054)
			(end -0.12065 -0.305054)
			(stroke
				(width 0.1)
				(type default)
			)
			(layer "F.Fab")
		)
		(pad "1" smd circle
			(at -0.40005 0 180)
			(size 0 0)
			(layers "F.Cu" "F.Mask" "F.Paste")
			(net "GPU_3V3IO_RSVD5_FFU_ISO")
		)
		(pad "2" smd circle
			(at 0.40005 0 180)
			(size 0 0)
			(layers "F.Cu" "F.Mask" "F.Paste")
			(net "GPU_3V3IO_RSVD5_FFU_ISO_R")
		)
	)
	(footprint ""
		(layer "F.Cu")
		(at 28.190698 -137.97661 90)
		(property "Reference" "PR4246"
			(at 0 0 90)
			(layer "F.SilkS")
			(hide yes)
			(effects
				(font
					(size 1.27 1.27)
				)
			)
		)
		(property "Value" ""
			(at 0 0 90)
			(layer "F.Fab")
			(effects
				(font
					(size 1.27 1.27)
				)
			)
		)
		(duplicate_pad_numbers_are_jumpers no)
		(fp_line
			(start 0.7874 -0.4064)
			(end 0.7874 0.4064)
			(stroke
				(width 0.1524)
				(type default)
			)
			(layer "F.SilkS")
		)
		(fp_line
			(start -0.7874 -0.4064)
			(end 0.7874 -0.4064)
			(stroke
				(width 0.1524)
				(type default)
			)
			(layer "F.SilkS")
		)
		(fp_line
			(start 0.7874 0.4064)
			(end -0.7874 0.4064)
			(stroke
				(width 0.1524)
				(type default)
			)
			(layer "F.SilkS")
		)
		(fp_line
			(start -0.7874 0.4064)
			(end -0.7874 -0.4064)
			(stroke
				(width 0.1524)
				(type default)
			)
			(layer "F.SilkS")
		)
		(fp_line
			(start -0.12065 -0.305054)
			(end -0.12065 -0.2794)
			(stroke
				(width 0.1)
				(type default)
			)
			(layer "F.Fab")
		)
		(fp_line
			(start -0.67945 -0.305054)
			(end -0.12065 -0.305054)
			(stroke
				(width 0.1)
				(type default)
			)
			(layer "F.Fab")
		)
		(fp_line
			(start 0.67945 -0.3048)
			(end 0.67945 0.3048)
			(stroke
				(width 0.1)
				(type default)
			)
			(layer "F.Fab")
		)
		(fp_line
			(start 0.12065 -0.3048)
			(end 0.67945 -0.3048)
			(stroke
				(width 0.1)
				(type default)
			)
			(layer "F.Fab")
		)
		(fp_line
			(start 0.12065 -0.2794)
			(end 0.12065 -0.3048)
			(stroke
				(width 0.1)
				(type default)
			)
			(layer "F.Fab")
		)
		(fp_line
			(start -0.12065 -0.2794)
			(end 0.12065 -0.2794)
			(stroke
				(width 0.1)
				(type default)
			)
			(layer "F.Fab")
		)
		(fp_line
			(start 0.120396 0.2794)
			(end -0.12065 0.2794)
			(stroke
				(width 0.1)
				(type default)
			)
			(layer "F.Fab")
		)
		(fp_line
			(start -0.12065 0.2794)
			(end -0.12065 0.3048)
			(stroke
				(width 0.1)
				(type default)
			)
			(layer "F.Fab")
		)
		(fp_line
			(start 0.67945 0.3048)
			(end 0.120396 0.3048)
			(stroke
				(width 0.1)
				(type default)
			)
			(layer "F.Fab")
		)
		(fp_line
			(start 0.120396 0.3048)
			(end 0.120396 0.2794)
			(stroke
				(width 0.1)
				(type default)
			)
			(layer "F.Fab")
		)
		(fp_line
			(start -0.12065 0.3048)
			(end -0.67945 0.3048)
			(stroke
				(width 0.1)
				(type default)
			)
			(layer "F.Fab")
		)
		(fp_line
			(start -0.67945 0.3048)
			(end -0.67945 -0.305054)
			(stroke
				(width 0.1)
				(type default)
			)
			(layer "F.Fab")
		)
		(pad "1" smd circle
			(at -0.40005 0 90)
			(size 0 0)
			(layers "F.Cu" "F.Mask" "F.Paste")
			(net "NC_PVCCINFAON_CPU1_ACSP7")
		)
		(pad "2" smd circle
			(at 0.40005 0 90)
			(size 0 0)
			(layers "F.Cu" "F.Mask" "F.Paste")
			(net "GND")
		)
	)
)
